# TIMECARD (Time Appliance Project (Time Card)) — schematic netlist excerpt (pin names and nets, part order shuffled) for the footprints in the layout excerpt that follows; sources: Cadence DE-HDL packaged netlist, KiCad conversion of R4006-B0001-02_R01.brd

R1991  RESISTOR  10KOHM 1%  pkg SMC_0402R_H016  page 16 : \1\ = XP3R3V_FPGA ; \2\ = EEPROM_SDA
R202  RESISTOR  4.7KOHM 1%  pkg SMC_0402R_H016  page 10 : \1\ = UNNAMED_127_MT25QL128ABA1ESES_2 ; \2\ = XP3R3V_FPGA

(kicad_pcb
	(version 20260206)
	(generator "pcbnew")
	(generator_version "10.0")
	(general
		(thickness 1.6)
		(legacy_teardrops no)
	)
	(paper "A4")
	(title_block
		(title "timecard-production-celestica-r4006 — R4006-B0001-02_R01.brd")
		(comment 1 "Time Appliance Project (Time Card) / footprints 989-990 of 1113")
	)
	(layers
		(0 "F.Cu" signal "TOP")
		(4 "In1.Cu" signal "L02_GND1")
		(6 "In2.Cu" signal "L03_SIG1")
		(8 "In3.Cu" signal "L04_GND2")
		(10 "In4.Cu" signal "L05_VCC1")
		(12 "In5.Cu" signal "L06_VCC2")
		(14 "In6.Cu" signal "L07_GND3")
		(16 "In7.Cu" signal "L08_SIG2")
		(18 "In8.Cu" signal "L09_GND4")
		(2 "B.Cu" signal "BOTTOM")
		(9 "F.Adhes" user "F.Adhesive")
		(11 "B.Adhes" user "B.Adhesive")
		(13 "F.Paste" user "Package Geometry/Pastemask Top")
		(15 "B.Paste" user "Package Geometry/Pastemask Bottom")
		(5 "F.SilkS" user "Ref Des/Silkscreen Top")
		(7 "B.SilkS" user "Ref Des/Silkscreen Bottom")
		(1 "F.Mask" user "Board Geometry/Soldermask Top")
		(3 "B.Mask" user "Board Geometry/Soldermask Bottom")
		(17 "Dwgs.User" user "User.Drawings")
		(19 "Cmts.User" user "User.Comments")
		(21 "Eco1.User" user "User.Eco1")
		(23 "Eco2.User" user "User.Eco2")
		(25 "Edge.Cuts" user "Board Geometry/Outline")
		(27 "Margin" user)
		(31 "F.CrtYd" user "Package Geometry/Place Bound Top")
		(29 "B.CrtYd" user "Package Geometry/Place Bound Bottom")
		(35 "F.Fab" user "Ref Des/Assembly Top")
		(33 "B.Fab" user "Ref Des/Assembly Bottom")
	)
	(footprint ""
		(layer "B.Cu")
		(at 30.34792 -16.73098 180)
		(property "Reference" "R1991"
			(at 0.75692 -1.27635 0)
			(unlocked yes)
			(layer "B.SilkS")
			(effects
				(font
					(size 0.7874 0.5842)
					(thickness 0.1524)
				)
				(justify mirror)
			)
		)
		(property "Value" "VAL*"
			(at -0.02032 2.13233 180)
			(unlocked yes)
			(layer "B.Fab")
			(hide yes)
			(effects
				(font
					(size 0.7874 0.5842)
					(thickness 0.1524)
				)
				(justify mirror)
			)
		)
		(property "Tolerance" "TOL*"
			(at -0.044704 3.05435 180)
			(unlocked yes)
			(layer "Cmts.User")
			(hide yes)
			(effects
				(font
					(size 0.7874 0.5842)
					(thickness 0.1524)
				)
				(justify mirror)
			)
		)
		(property "User Part Number" "PARTNUM*"
			(at -0.02032 4.024884 180)
			(unlocked yes)
			(layer "Cmts.User")
			(hide yes)
			(effects
				(font
					(size 0.7874 0.5842)
					(thickness 0.1524)
				)
				(justify mirror)
			)
		)
		(property "Device Type" "RESISTOR-G155-11002-01,10KOHM,A"
			(at -0.008382 1.210564 180)
			(unlocked yes)
			(layer "B.Fab")
			(hide yes)
			(effects
				(font
					(size 0.7874 0.5842)
					(thickness 0.1524)
				)
				(justify mirror)
			)
		)
		(duplicate_pad_numbers_are_jumpers no)
		(fp_line
			(start 1.143 0.5588)
			(end -1.143 0.5588)
			(stroke
				(width 0.1)
				(type default)
			)
			(layer "B.SilkS")
		)
		(fp_line
			(start 1.143 -0.5588)
			(end 1.143 0.5588)
			(stroke
				(width 0.1)
				(type default)
			)
			(layer "B.SilkS")
		)
		(fp_line
			(start -1.143 0.5588)
			(end -1.143 -0.5588)
			(stroke
				(width 0.1)
				(type default)
			)
			(layer "B.SilkS")
		)
		(fp_line
			(start -1.143 -0.5588)
			(end 1.143 -0.5588)
			(stroke
				(width 0.1)
				(type default)
			)
			(layer "B.SilkS")
		)
		(fp_rect
			(start 1.143 -0.5588)
			(end -1.143 0.5588)
			(stroke
				(width 0)
				(type default)
			)
			(fill no)
			(layer "B.CrtYd")
		)
		(fp_line
			(start 0.508 0.3048)
			(end -0.508 0.3048)
			(stroke
				(width 0.1)
				(type default)
			)
			(layer "B.Fab")
		)
		(fp_line
			(start 0.508 -0.3048)
			(end 0.508 0.3048)
			(stroke
				(width 0.1)
				(type default)
			)
			(layer "B.Fab")
		)
		(fp_line
			(start -0.508 0.3048)
			(end -0.508 -0.3048)
			(stroke
				(width 0.1)
				(type default)
			)
			(layer "B.Fab")
		)
		(fp_line
			(start -0.508 -0.3048)
			(end 0.508 -0.3048)
			(stroke
				(width 0.1)
				(type default)
			)
			(layer "B.Fab")
		)
		(pad "1" smd rect
			(at 0.5334 0)
			(size 0.7112 0.6096)
			(layers "B.Cu" "B.Mask" "B.Paste")
			(net "XP3R3V_FPGA")
		)
		(pad "2" smd rect
			(at -0.5334 0)
			(size 0.7112 0.6096)
			(layers "B.Cu" "B.Mask" "B.Paste")
			(net "EEPROM_SDA")
		)
		(zone
			(layer "B.Cu")
			(hatch none 0.5)
			(connect_pads
				(clearance 0)
			)
			(min_thickness 0.25)
			(keepout
				(tracks allowed)
				(vias not_allowed)
				(pads allowed)
				(copperpour not_allowed)
				(footprints allowed)
			)
			(placement
				(enabled no)
				(sheetname "")
			)
			(fill
				(thermal_gap 0.5)
				(thermal_bridge_width 0.5)
				(island_removal_mode 0)
			)
			(polygon
				(pts
					(xy 30.27172 -16.42618) (xy 30.42412 -16.42618) (xy 30.42412 -17.03578) (xy 30.27172 -17.03578)
				)
			)
		)
	)
	(footprint ""
		(layer "B.Cu")
		(at 88.519 -83.312 180)
		(property "Reference" "R202"
			(at -0.254 5.54863 0)
			(unlocked yes)
			(layer "B.SilkS")
			(effects
				(font
					(size 0.7874 0.5842)
					(thickness 0.1524)
				)
				(justify mirror)
			)
		)
		(property "Value" "VAL*"
			(at -0.02032 2.13233 180)
			(unlocked yes)
			(layer "B.Fab")
			(hide yes)
			(effects
				(font
					(size 0.7874 0.5842)
					(thickness 0.1524)
				)
				(justify mirror)
			)
		)
		(property "Tolerance" "TOL*"
			(at -0.044704 3.05435 180)
			(unlocked yes)
			(layer "Cmts.User")
			(hide yes)
			(effects
				(font
					(size 0.7874 0.5842)
					(thickness 0.1524)
				)
				(justify mirror)
			)
		)
		(property "User Part Number" "PARTNUM*"
			(at -0.02032 4.024884 180)
			(unlocked yes)
			(layer "Cmts.User")
			(hide yes)
			(effects
				(font
					(size 0.7874 0.5842)
					(thickness 0.1524)
				)
				(justify mirror)
			)
		)
		(property "Device Type" "RESISTOR-G155-14701-01,4.7KOHMA"
			(at -0.008382 1.210564 180)
			(unlocked yes)
			(layer "B.Fab")
			(hide yes)
			(effects
				(font
					(size 0.7874 0.5842)
					(thickness 0.1524)
				)
				(justify mirror)
			)
		)
		(duplicate_pad_numbers_are_jumpers no)
		(fp_line
			(start 1.143 0.5588)
			(end -1.143 0.5588)
			(stroke
				(width 0.1)
				(type default)
			)
			(layer "B.SilkS")
		)
		(fp_line
			(start 1.143 -0.5588)
			(end 1.143 0.5588)
			(stroke
				(width 0.1)
				(type default)
			)
			(layer "B.SilkS")
		)
		(fp_line
			(start -1.143 0.5588)
			(end -1.143 -0.5588)
			(stroke
				(width 0.1)
				(type default)
			)
			(layer "B.SilkS")
		)
		(fp_line
			(start -1.143 -0.5588)
			(end 1.143 -0.5588)
			(stroke
				(width 0.1)
				(type default)
			)
			(layer "B.SilkS")
		)
		(fp_rect
			(start 1.143 -0.5588)
			(end -1.143 0.5588)
			(stroke
				(width 0)
				(type default)
			)
			(fill no)
			(layer "B.CrtYd")
		)
		(fp_line
			(start 0.508 0.3048)
			(end -0.508 0.3048)
			(stroke
				(width 0.1)
				(type default)
			)
			(layer "B.Fab")
		)
		(fp_line
			(start 0.508 -0.3048)
			(end 0.508 0.3048)
			(stroke
				(width 0.1)
				(type default)
			)
			(layer "B.Fab")
		)
		(fp_line
			(start -0.508 0.3048)
			(end -0.508 -0.3048)
			(stroke
				(width 0.1)
				(type default)
			)
			(layer "B.Fab")
		)
		(fp_line
			(start -0.508 -0.3048)
			(end 0.508 -0.3048)
			(stroke
				(width 0.1)
				(type default)
			)
			(layer "B.Fab")
		)
		(pad "1" smd rect
			(at 0.5334 0)
			(size 0.7112 0.6096)
			(layers "B.Cu" "B.Mask" "B.Paste")
			(net "UNNAMED_127_MT25QL128ABA1ESES_2")
		)
		(pad "2" smd rect
			(at -0.5334 0)
			(size 0.7112 0.6096)
			(layers "B.Cu" "B.Mask" "B.Paste")
			(net "XP3R3V_FPGA")
		)
		(zone
			(layer "B.Cu")
			(hatch none 0.5)
			(connect_pads
				(clearance 0)
			)
			(min_thickness 0.25)
			(keepout
				(tracks allowed)
				(vias not_allowed)
				(pads allowed)
				(copperpour not_allowed)
				(footprints allowed)
			)
			(placement
				(enabled no)
				(sheetname "")
			)
			(fill
				(thermal_gap 0.5)
				(thermal_bridge_width 0.5)
				(island_removal_mode 0)
			)
			(polygon
				(pts
					(xy 88.4428 -83.0072) (xy 88.5952 -83.0072) (xy 88.5952 -83.6168) (xy 88.4428 -83.6168)
				)
			)
		)
	)
)
